(kicad_pcb
	(version 20211014)
	(generator pcbnew)
	(general
    (thickness 1.6)
  )
	(paper "A4")
	(title_block
    (title "SA800U (Snapdragon 845) Baseboard")
    (date "2023-10-19")
    (rev "1.0.3")
    (company "Antmicro Ltd.")
    (comment 1 "www.antmicro.com")
		(comment 9 "footprints 234-242 of 589")
	)
	(layers
    (0 "F.Cu" signal)
    (1 "In1.Cu" power)
    (2 "In2.Cu" signal)
    (3 "In3.Cu" signal)
    (4 "In4.Cu" power)
    (31 "B.Cu" signal)
    (32 "B.Adhes" user "B.Adhesive")
    (33 "F.Adhes" user "F.Adhesive")
    (34 "B.Paste" user)
    (35 "F.Paste" user)
    (36 "B.SilkS" user "B.Silkscreen")
    (37 "F.SilkS" user "F.Silkscreen")
    (38 "B.Mask" user)
    (39 "F.Mask" user)
    (40 "Dwgs.User" user "User.Drawings")
    (41 "Cmts.User" user "User.Comments")
    (42 "Eco1.User" user "User.Eco1")
    (43 "Eco2.User" user "User.Eco2")
    (44 "Edge.Cuts" user)
    (45 "Margin" user)
    (46 "B.CrtYd" user "B.Courtyard")
    (47 "F.CrtYd" user "F.Courtyard")
    (48 "B.Fab" user)
    (49 "F.Fab" user)
  )
	(footprint "sa800u-baseboard-hw-footprints:SOT-23-3" (layer "F.Cu")
    (tedit 5D5D4314)
    (at 84.4 104.7 -90)
    (property "Author" "Antmicro")
    (property "License" "Apache-2.0")
    (property "MPN" "BSS84")
    (property "Manufacturer" "ON Semiconductor")
    (property "Sheetfile" "psu.kicad_sch")
    (property "Sheetname" "PSU")
    (attr smd)
    (fp_text reference "Q13" (at 1.68 -0.32) (layer "F.SilkS")
      (effects (font (size 0.7 0.7) (thickness 0.15)) (justify left bottom))
    )
    (fp_text value "BSS84" (at -1.9 2.7 -90) (layer "F.Fab")
      (effects (font (size 0.7 0.7) (thickness 0.15)) (justify left bottom))
    )
    (fp_text user "License: Apache-2.0" (at -1.8 6.8 -90) (layer "F.Fab") hide
      (effects (font (size 0.7 0.7) (thickness 0.15)) (justify left bottom))
    )
    (fp_text user "${REFERENCE}" (at -1.837 4 -90) (layer "F.Fab") hide
      (effects (font (size 0.7 0.7) (thickness 0.15)) (justify left bottom))
    )
    (fp_text user "Author: Antmicro" (at -1.837 5.3 -90) (layer "F.Fab") hide
      (effects (font (size 0.7 0.7) (thickness 0.15)) (justify left bottom))
    )
    (fp_line (start 0.7 0.4) (end 0.7 1.5) (layer "F.SilkS") (width 0.15))
    (fp_line (start 0.7 -1.5) (end -0.7 -1.5) (layer "F.SilkS") (width 0.15))
    (fp_line (start -0.85 -1.35) (end -0.7 -1.5) (layer "F.SilkS") (width 0.15))
    (fp_line (start -1.45 -1.35) (end -0.85 -1.35) (layer "F.SilkS") (width 0.15))
    (fp_line (start 0.7 1.5) (end -0.7 1.5) (layer "F.SilkS") (width 0.15))
    (fp_line (start 0.7 -0.4) (end 0.7 -1.5) (layer "F.SilkS") (width 0.15))
    (fp_line (start -0.7 1.5) (end -0.7 1.35) (layer "F.SilkS") (width 0.15))
    (fp_line (start -0.85 0.5) (end -0.85 -0.5) (layer "F.CrtYd") (width 0.05))
    (fp_line (start -0.9 -1.6) (end -0.9 -1.4) (layer "F.CrtYd") (width 0.05))
    (fp_line (start -1.75 0.5) (end -0.85 0.5) (layer "F.CrtYd") (width 0.05))
    (fp_line (start 0.85 0.45) (end 0.85 1.65) (layer "F.CrtYd") (width 0.05))
    (fp_line (start 0.825 -1.6) (end 0.825 -0.45) (layer "F.CrtYd") (width 0.05))
    (fp_line (start 1.75 0.45) (end 0.85 0.45) (layer "F.CrtYd") (width 0.05))
    (fp_line (start 0.85 1.65) (end -0.85 1.65) (layer "F.CrtYd") (width 0.05))
    (fp_line (start -0.85 1.65) (end -0.85 1.4) (layer "F.CrtYd") (width 0.05))
    (fp_line (start -0.85 1.4) (end -1.75 1.4) (layer "F.CrtYd") (width 0.05))
    (fp_line (start -0.9 -1.6) (end 0.825 -1.6) (layer "F.CrtYd") (width 0.05))
    (fp_line (start -1.75 1.4) (end -1.75 0.5) (layer "F.CrtYd") (width 0.05))
    (fp_line (start -1.75 -0.5) (end -1.75 -1.4) (layer "F.CrtYd") (width 0.05))
    (fp_line (start -0.9 -1.4) (end -1.75 -1.4) (layer "F.CrtYd") (width 0.05))
    (fp_line (start 0.825 -0.45) (end 1.75 -0.45) (layer "F.CrtYd") (width 0.05))
    (fp_line (start -0.85 -0.5) (end -1.75 -0.5) (layer "F.CrtYd") (width 0.05))
    (fp_line (start 1.75 -0.45) (end 1.75 0.45) (layer "F.CrtYd") (width 0.05))
    (fp_line (start -0.712 1.519) (end 0.688 1.519) (layer "F.Fab") (width 0.15))
    (fp_line (start -0.437 -1.526) (end 0.688 -1.526) (layer "F.Fab") (width 0.15))
    (fp_line (start -0.437 -1.526) (end -0.712 -1.325) (layer "F.Fab") (width 0.15))
    (fp_line (start 0.688 1.519) (end 0.688 -1.52) (layer "F.Fab") (width 0.15))
    (fp_line (start -0.712 -1.325) (end -0.712 1.523) (layer "F.Fab") (width 0.15))
    (pad "1" smd roundrect (at -1.1 -0.951 270) (size 1 0.6) (layers "F.Cu" "F.Paste" "F.Mask") (roundrect_rratio 0.15)
      (net 340 "/PSU/POE_VALID") (pinfunction "G") (pintype "bidirectional"))
    (pad "2" smd roundrect (at -1.1 0.949 270) (size 1 0.6) (layers "F.Cu" "F.Paste" "F.Mask") (roundrect_rratio 0.15)
      (net 1 "GND") (pinfunction "D") (pintype "bidirectional"))
    (pad "3" smd roundrect (at 1.1 -0.0005 270) (size 1 0.6) (layers "F.Cu" "F.Paste" "F.Mask") (roundrect_rratio 0.15)
      (net 347 "Net-(Q13-Pad3)") (pinfunction "S") (pintype "bidirectional"))
  )
	(footprint "sa800u-baseboard-hw-footprints:D_0201_0603Metric" (layer "F.Cu")
    (tedit 62026EA2)
    (at 91.1 138.4)
    (property "Author" "Antmicro")
    (property "License" "Apache-2.0")
    (property "MPN" "PESD18VF1BSFYL")
    (property "Manufacturer" "Nexperia")
    (property "Sheetfile" "usb-pd.kicad_sch")
    (property "Sheetname" "USB-PD")
    (attr smd)
    (fp_text reference "D33" (at -1.03 -0.43) (layer "F.SilkS")
      (effects (font (size 0.7 0.7) (thickness 0.15)) (justify left bottom))
    )
    (fp_text value "PESD18VF1BSFYL" (at 0 1.25) (layer "F.Fab")
      (effects (font (size 0.7 0.7) (thickness 0.15)) (justify left bottom))
    )
    (fp_text user "License: Apache-2.0" (at -0.72 5.281) (layer "F.Fab") hide
      (effects (font (size 0.7 0.7) (thickness 0.15)) (justify left bottom))
    )
    (fp_text user "${REFERENCE}" (at -0.72 2.882) (layer "F.Fab") hide
      (effects (font (size 0.7 0.7) (thickness 0.15)) (justify left bottom))
    )
    (fp_text user "Author: Antmicro" (at -0.72 4.081) (layer "F.Fab") hide
      (effects (font (size 0.7 0.7) (thickness 0.15)) (justify left bottom))
    )
    (fp_line (start -0.025 -0.201) (end -0.025 0.199) (layer "F.SilkS") (width 0.12))
    (fp_rect (start -0.5 -0.3) (end 0.5 0.3) (layer "F.CrtYd") (width 0.05) (fill none))
    (fp_line (start -0.32 -0.172) (end 0.32 -0.172) (layer "F.Fab") (width 0.15))
    (fp_line (start -0.32 0.17) (end 0.32 0.17) (layer "F.Fab") (width 0.15))
    (fp_line (start 0.32 -0.172) (end 0.32 0.17) (layer "F.Fab") (width 0.15))
    (fp_line (start -0.32 -0.172) (end -0.32 0.17) (layer "F.Fab") (width 0.15))
    (pad "1" smd roundrect (at -0.282 0) (size 0.38 0.4) (layers "F.Cu" "F.Paste" "F.Mask") (roundrect_rratio 0.05)
      (net 144 "/USB-PD/PD_CC2") (pinfunction "1") (pintype "input"))
    (pad "2" smd rect (at 0.28 0) (size 0.38 0.4) (layers "F.Cu" "F.Paste" "F.Mask")
      (net 1 "GND") (pinfunction "2") (pintype "input"))
  )
	(footprint "sa800u-baseboard-hw-footprints:D_0201_0603Metric" (layer "F.Cu")
    (tedit 62026EA2)
    (at 90.1 139.4 180)
    (property "Author" "Antmicro")
    (property "License" "Apache-2.0")
    (property "MPN" "PESD18VF1BSFYL")
    (property "Manufacturer" "Nexperia")
    (property "Sheetfile" "usb-pd.kicad_sch")
    (property "Sheetname" "USB-PD")
    (attr smd)
    (fp_text reference "D34" (at -0.4 -0.24 180) (layer "F.SilkS")
      (effects (font (size 0.7 0.7) (thickness 0.15)) (justify left bottom))
    )
    (fp_text value "PESD18VF1BSFYL" (at 0 1.25 180) (layer "F.Fab")
      (effects (font (size 0.7 0.7) (thickness 0.15)) (justify left bottom))
    )
    (fp_text user "Author: Antmicro" (at -0.72 4.081 180) (layer "F.Fab") hide
      (effects (font (size 0.7 0.7) (thickness 0.15)) (justify left bottom))
    )
    (fp_text user "License: Apache-2.0" (at -0.72 5.281 180) (layer "F.Fab") hide
      (effects (font (size 0.7 0.7) (thickness 0.15)) (justify left bottom))
    )
    (fp_text user "${REFERENCE}" (at -0.72 2.882 180) (layer "F.Fab") hide
      (effects (font (size 0.7 0.7) (thickness 0.15)) (justify left bottom))
    )
    (fp_line (start -0.025 -0.201) (end -0.025 0.199) (layer "F.SilkS") (width 0.12))
    (fp_rect (start -0.5 -0.3) (end 0.5 0.3) (layer "F.CrtYd") (width 0.05) (fill none))
    (fp_line (start -0.32 -0.172) (end 0.32 -0.172) (layer "F.Fab") (width 0.15))
    (fp_line (start 0.32 -0.172) (end 0.32 0.17) (layer "F.Fab") (width 0.15))
    (fp_line (start -0.32 0.17) (end 0.32 0.17) (layer "F.Fab") (width 0.15))
    (fp_line (start -0.32 -0.172) (end -0.32 0.17) (layer "F.Fab") (width 0.15))
    (pad "1" smd roundrect (at -0.282 0 180) (size 0.38 0.4) (layers "F.Cu" "F.Paste" "F.Mask") (roundrect_rratio 0.05)
      (net 143 "/USB-PD/PD_CC1") (pinfunction "1") (pintype "input"))
    (pad "2" smd rect (at 0.28 0 180) (size 0.38 0.4) (layers "F.Cu" "F.Paste" "F.Mask")
      (net 1 "GND") (pinfunction "2") (pintype "input"))
  )
	(footprint "sa800u-baseboard-hw-footprints:D_0201_0603Metric" (layer "F.Cu")
    (tedit 62026EA2)
    (at 151.65 107.95)
    (property "Author" "Antmicro")
    (property "License" "Apache-2.0")
    (property "MPN" "PESD2V5Y1BSFYL")
    (property "Manufacturer" "Nexperia")
    (property "Sheetfile" "som.kicad_sch")
    (property "Sheetname" "SoM")
    (attr smd)
    (fp_text reference "D20" (at 0.48 0.2) (layer "F.SilkS")
      (effects (font (size 0.7 0.7) (thickness 0.15)) (justify left bottom))
    )
    (fp_text value "PESD2V5Y1BSFYL" (at 0 1.25) (layer "F.Fab")
      (effects (font (size 0.7 0.7) (thickness 0.15)) (justify left bottom))
    )
    (fp_text user "Author: Antmicro" (at -0.72 4.081) (layer "F.Fab") hide
      (effects (font (size 0.7 0.7) (thickness 0.15)) (justify left bottom))
    )
    (fp_text user "License: Apache-2.0" (at -0.72 5.281) (layer "F.Fab") hide
      (effects (font (size 0.7 0.7) (thickness 0.15)) (justify left bottom))
    )
    (fp_text user "${REFERENCE}" (at -0.72 2.882) (layer "F.Fab") hide
      (effects (font (size 0.7 0.7) (thickness 0.15)) (justify left bottom))
    )
    (fp_line (start -0.025 -0.201) (end -0.025 0.199) (layer "F.SilkS") (width 0.12))
    (fp_rect (start -0.5 -0.3) (end 0.5 0.3) (layer "F.CrtYd") (width 0.05) (fill none))
    (fp_line (start -0.32 -0.172) (end -0.32 0.17) (layer "F.Fab") (width 0.15))
    (fp_line (start -0.32 -0.172) (end 0.32 -0.172) (layer "F.Fab") (width 0.15))
    (fp_line (start -0.32 0.17) (end 0.32 0.17) (layer "F.Fab") (width 0.15))
    (fp_line (start 0.32 -0.172) (end 0.32 0.17) (layer "F.Fab") (width 0.15))
    (pad "1" smd roundrect (at -0.282 0) (size 0.38 0.4) (layers "F.Cu" "F.Paste" "F.Mask") (roundrect_rratio 0.05)
      (net 343 "/SoM/VOL_DOWN_R") (pinfunction "1") (pintype "input"))
    (pad "2" smd rect (at 0.28 0) (size 0.38 0.4) (layers "F.Cu" "F.Paste" "F.Mask")
      (net 1 "GND") (pinfunction "2") (pintype "input"))
  )
	(footprint "sa800u-baseboard-hw-footprints:D_0201_0603Metric" (layer "F.Cu")
    (tedit 62026EA2)
    (at 151.9 95.9)
    (property "Author" "Antmicro")
    (property "License" "Apache-2.0")
    (property "MPN" "PESD2V5Y1BSFYL")
    (property "Manufacturer" "Nexperia")
    (property "Sheetfile" "som.kicad_sch")
    (property "Sheetname" "SoM")
    (attr smd)
    (fp_text reference "D17" (at 0.48 0.18) (layer "F.SilkS")
      (effects (font (size 0.7 0.7) (thickness 0.15)) (justify left bottom))
    )
    (fp_text value "PESD2V5Y1BSFYL" (at 0 1.25) (layer "F.Fab")
      (effects (font (size 0.7 0.7) (thickness 0.15)) (justify left bottom))
    )
    (fp_text user "License: Apache-2.0" (at -0.72 5.281) (layer "F.Fab") hide
      (effects (font (size 0.7 0.7) (thickness 0.15)) (justify left bottom))
    )
    (fp_text user "Author: Antmicro" (at -0.72 4.081) (layer "F.Fab") hide
      (effects (font (size 0.7 0.7) (thickness 0.15)) (justify left bottom))
    )
    (fp_text user "${REFERENCE}" (at -0.72 2.882) (layer "F.Fab") hide
      (effects (font (size 0.7 0.7) (thickness 0.15)) (justify left bottom))
    )
    (fp_line (start -0.025 -0.201) (end -0.025 0.199) (layer "F.SilkS") (width 0.12))
    (fp_rect (start -0.5 -0.3) (end 0.5 0.3) (layer "F.CrtYd") (width 0.05) (fill none))
    (fp_line (start 0.32 -0.172) (end 0.32 0.17) (layer "F.Fab") (width 0.15))
    (fp_line (start -0.32 -0.172) (end -0.32 0.17) (layer "F.Fab") (width 0.15))
    (fp_line (start -0.32 -0.172) (end 0.32 -0.172) (layer "F.Fab") (width 0.15))
    (fp_line (start -0.32 0.17) (end 0.32 0.17) (layer "F.Fab") (width 0.15))
    (pad "1" smd roundrect (at -0.282 0) (size 0.38 0.4) (layers "F.Cu" "F.Paste" "F.Mask") (roundrect_rratio 0.05)
      (net 344 "/SoM/HOME_KEY_R") (pinfunction "1") (pintype "input"))
    (pad "2" smd rect (at 0.28 0) (size 0.38 0.4) (layers "F.Cu" "F.Paste" "F.Mask")
      (net 1 "GND") (pinfunction "2") (pintype "input"))
  )
	(footprint "sa800u-baseboard-hw-footprints:D_0201_0603Metric" (layer "F.Cu")
    (tedit 62026EA2)
    (at 151.63 101.9)
    (property "Author" "Antmicro")
    (property "License" "Apache-2.0")
    (property "MPN" "PESD2V5Y1BSFYL")
    (property "Manufacturer" "Nexperia")
    (property "Sheetfile" "som.kicad_sch")
    (property "Sheetname" "SoM")
    (attr smd)
    (fp_text reference "D18" (at 0.42 0.25) (layer "F.SilkS")
      (effects (font (size 0.7 0.7) (thickness 0.15)) (justify left bottom))
    )
    (fp_text value "PESD2V5Y1BSFYL" (at 0 1.25) (layer "F.Fab")
      (effects (font (size 0.7 0.7) (thickness 0.15)) (justify left bottom))
    )
    (fp_text user "${REFERENCE}" (at -0.72 2.882) (layer "F.Fab") hide
      (effects (font (size 0.7 0.7) (thickness 0.15)) (justify left bottom))
    )
    (fp_text user "Author: Antmicro" (at -0.72 4.081) (layer "F.Fab") hide
      (effects (font (size 0.7 0.7) (thickness 0.15)) (justify left bottom))
    )
    (fp_text user "License: Apache-2.0" (at -0.72 5.281) (layer "F.Fab") hide
      (effects (font (size 0.7 0.7) (thickness 0.15)) (justify left bottom))
    )
    (fp_line (start -0.025 -0.201) (end -0.025 0.199) (layer "F.SilkS") (width 0.12))
    (fp_rect (start -0.5 -0.3) (end 0.5 0.3) (layer "F.CrtYd") (width 0.05) (fill none))
    (fp_line (start -0.32 -0.172) (end 0.32 -0.172) (layer "F.Fab") (width 0.15))
    (fp_line (start 0.32 -0.172) (end 0.32 0.17) (layer "F.Fab") (width 0.15))
    (fp_line (start -0.32 0.17) (end 0.32 0.17) (layer "F.Fab") (width 0.15))
    (fp_line (start -0.32 -0.172) (end -0.32 0.17) (layer "F.Fab") (width 0.15))
    (pad "1" smd roundrect (at -0.282 0) (size 0.38 0.4) (layers "F.Cu" "F.Paste" "F.Mask") (roundrect_rratio 0.05)
      (net 345 "/SoM/VOL_UP_R") (pinfunction "1") (pintype "input"))
    (pad "2" smd rect (at 0.28 0) (size 0.38 0.4) (layers "F.Cu" "F.Paste" "F.Mask")
      (net 1 "GND") (pinfunction "2") (pintype "input"))
  )
	(footprint "sa800u-baseboard-hw-footprints:D_0201_0603Metric" (layer "F.Cu")
    (tedit 62026EA2)
    (at 151.65 113.9)
    (property "Author" "Antmicro")
    (property "License" "Apache-2.0")
    (property "MPN" "PESD2V5Y1BSFYL")
    (property "Manufacturer" "Nexperia")
    (property "Sheetfile" "som.kicad_sch")
    (property "Sheetname" "SoM")
    (attr smd)
    (fp_text reference "D19" (at -0.66 1.18) (layer "F.SilkS")
      (effects (font (size 0.7 0.7) (thickness 0.15)) (justify left bottom))
    )
    (fp_text value "PESD2V5Y1BSFYL" (at 0 1.25) (layer "F.Fab")
      (effects (font (size 0.7 0.7) (thickness 0.15)) (justify left bottom))
    )
    (fp_text user "${REFERENCE}" (at -0.72 2.882) (layer "F.Fab") hide
      (effects (font (size 0.7 0.7) (thickness 0.15)) (justify left bottom))
    )
    (fp_text user "Author: Antmicro" (at -0.72 4.081) (layer "F.Fab") hide
      (effects (font (size 0.7 0.7) (thickness 0.15)) (justify left bottom))
    )
    (fp_text user "License: Apache-2.0" (at -0.72 5.281) (layer "F.Fab") hide
      (effects (font (size 0.7 0.7) (thickness 0.15)) (justify left bottom))
    )
    (fp_line (start -0.025 -0.201) (end -0.025 0.199) (layer "F.SilkS") (width 0.12))
    (fp_rect (start -0.5 -0.3) (end 0.5 0.3) (layer "F.CrtYd") (width 0.05) (fill none))
    (fp_line (start -0.32 -0.172) (end 0.32 -0.172) (layer "F.Fab") (width 0.15))
    (fp_line (start -0.32 -0.172) (end -0.32 0.17) (layer "F.Fab") (width 0.15))
    (fp_line (start -0.32 0.17) (end 0.32 0.17) (layer "F.Fab") (width 0.15))
    (fp_line (start 0.32 -0.172) (end 0.32 0.17) (layer "F.Fab") (width 0.15))
    (pad "1" smd roundrect (at -0.282 0) (size 0.38 0.4) (layers "F.Cu" "F.Paste" "F.Mask") (roundrect_rratio 0.05)
      (net 346 "/SoM/PWR_R") (pinfunction "1") (pintype "input"))
    (pad "2" smd rect (at 0.28 0) (size 0.38 0.4) (layers "F.Cu" "F.Paste" "F.Mask")
      (net 1 "GND") (pinfunction "2") (pintype "input"))
  )
	(footprint "sa800u-baseboard-hw-footprints:C_0402_1005Metric" (layer "F.Cu")
    (tedit 616D63CF)
    (at 97 101.35 -90)
    (descr "Capacitor SMD 0402")
    (tags "capacitor SMD 0402")
    (property "Author" "Antmicro")
    (property "DNP" "DNP")
    (property "Dielectric" "")
    (property "License" "Apache-2.0")
    (property "MPN" "GRM155R61A475MEAAD")
    (property "Manufacturer" "Murata")
    (property "Sheetfile" "ethernet-controller.kicad_sch")
    (property "Sheetname" "Ethernet Controller")
    (property "Val" "4u7")
    (property "Voltage" "")
    (attr exclude_from_pos_files)
    (fp_text reference "C10" (at -0.87 -0.38 -90) (layer "F.SilkS")
      (effects (font (size 0.7 0.7) (thickness 0.15)) (justify left bottom))
    )
    (fp_text value "C_4u7_0402" (at 0 1.4 -90) (layer "F.Fab")
      (effects (font (size 0.7 0.7) (thickness 0.15)) (justify left bottom))
    )
    (fp_text user "License: Apache-2.0" (at -0.932 5.17 -90) (layer "F.Fab") hide
      (effects (font (size 0.7 0.7) (thickness 0.15)) (justify left bottom))
    )
    (fp_text user "${REFERENCE}" (at -0.932 3.168 -90) (layer "F.Fab") hide
      (effects (font (size 0.7 0.7) (thickness 0.15)) (justify left bottom))
    )
    (fp_text user "Author: Antmicro" (at -0.932 4.17 -90) (layer "F.Fab") hide
      (effects (font (size 0.7 0.7) (thickness 0.15)) (justify left bottom))
    )
    (fp_rect (start -0.94 -0.47) (end 0.94 0.47) (layer "F.CrtYd") (width 0.05) (fill none))
    (fp_rect (start -0.499 -0.249) (end 0.499 0.249) (layer "F.Fab") (width 0.15) (fill none))
    (pad "1" smd roundrect (at -0.484 0 270) (size 0.59 0.64) (layers "F.Cu" "F.Paste" "F.Mask") (roundrect_rratio 0.25)
      (net 177 "/Ethernet Controller/ETH_3V3") (pintype "passive"))
    (pad "2" smd roundrect (at 0.484 0 270) (size 0.59 0.64) (layers "F.Cu" "F.Paste" "F.Mask") (roundrect_rratio 0.25)
      (net 1 "GND") (pintype "passive"))
  )
	(footprint "sa800u-baseboard-hw-footprints:C_0402_1005Metric" (layer "F.Cu")
    (tedit 616D63CF)
    (at 115.11 93.8 -90)
    (descr "Capacitor SMD 0402")
    (tags "capacitor SMD 0402")
    (property "Author" "Antmicro")
    (property "Dielectric" "X5R")
    (property "License" "Apache-2.0")
    (property "MPN" "GRM155R61H104KE14D")
    (property "Manufacturer" "Murata")
    (property "Sheetfile" "camera-interface.kicad_sch")
    (property "Sheetname" "Camera Interface")
    (property "Val" "100n")
    (property "Voltage" "50V")
    (attr smd)
    (fp_text reference "C109" (at 1.26 -1.27 -90) (layer "F.SilkS")
      (effects (font (size 0.7 0.7) (thickness 0.15)) (justify left bottom))
    )
    (fp_text value "C_100n_0402" (at 0 1.4 -90) (layer "F.Fab")
      (effects (font (size 0.7 0.7) (thickness 0.15)) (justify left bottom))
    )
    (fp_text user "Author: Antmicro" (at -0.932 4.17 -90) (layer "F.Fab") hide
      (effects (font (size 0.7 0.7) (thickness 0.15)) (justify left bottom))
    )
    (fp_text user "${REFERENCE}" (at -0.932 3.168 -90) (layer "F.Fab") hide
      (effects (font (size 0.7 0.7) (thickness 0.15)) (justify left bottom))
    )
    (fp_text user "License: Apache-2.0" (at -0.932 5.17 -90) (layer "F.Fab") hide
      (effects (font (size 0.7 0.7) (thickness 0.15)) (justify left bottom))
    )
    (fp_rect (start -0.94 -0.47) (end 0.94 0.47) (layer "F.CrtYd") (width 0.05) (fill none))
    (fp_rect (start -0.499 -0.249) (end 0.499 0.249) (layer "F.Fab") (width 0.15) (fill none))
    (pad "1" smd roundrect (at -0.484 0 270) (size 0.59 0.64) (layers "F.Cu" "F.Paste" "F.Mask") (roundrect_rratio 0.25)
      (net 231 "/Camera Interface/3V3_CAM") (pintype "passive"))
    (pad "2" smd roundrect (at 0.484 0 270) (size 0.59 0.64) (layers "F.Cu" "F.Paste" "F.Mask") (roundrect_rratio 0.25)
      (net 1 "GND") (pintype "passive"))
  )
)
